FILE_TYPE=LIBRARY_PARTS;
primitive 'INA230AIRGTR';
  pin
    'VS':
      PIN_NUMBER='(9)';
      PINUSE='POWER';
      NO_LOAD_CHECK='Both';
      NO_IO_CHECK='Both';
      NO_ASSERT_CHECK='TRUE';
      NO_DIR_CHECK='TRUE';
      ALLOW_CONNECT='TRUE';
    'A1':
      PIN_NUMBER='(1)';
      INPUT_LOAD='(-0.01,0.01)';
    'A0':
      PIN_NUMBER='(2)';
      INPUT_LOAD='(-0.01,0.01)';
    'SCL':
      PIN_NUMBER='(5)';
      INPUT_LOAD='(-0.01,0.01)';
    'SDA':
      PIN_NUMBER='(4)';
      BIDIRECTIONAL='TRUE';
      INPUT_LOAD='(-0.01,0.01)';
      OUTPUT_LOAD='(1.0,-1.0)';
    'BUS':
      PIN_NUMBER='(11)';
      INPUT_LOAD='(-0.01,0.01)';
    'IN+':
      PIN_NUMBER='(13)';
      INPUT_LOAD='(-0.01,0.01)';
    'IN-':
      PIN_NUMBER='(12)';
      INPUT_LOAD='(-0.01,0.01)';
    'ALERT':
      PIN_NUMBER='(3)';
      OUTPUT_LOAD='(1.0,-1.0)';
    'NC0':
      PIN_NUMBER='(6)';
      OUTPUT_LOAD='(1.0,-1.0)';
    'NC1':
      PIN_NUMBER='(7)';
      OUTPUT_LOAD='(1.0,-1.0)';
    'NC2':
      PIN_NUMBER='(8)';
      OUTPUT_LOAD='(1.0,-1.0)';
    'NC3':
      PIN_NUMBER='(14)';
      OUTPUT_LOAD='(1.0,-1.0)';
    'NC4':
      PIN_NUMBER='(15)';
      OUTPUT_LOAD='(1.0,-1.0)';
    'NC5':
      PIN_NUMBER='(16)';
      OUTPUT_LOAD='(1.0,-1.0)';
    'GND':
      PIN_NUMBER='(10)';
      PINUSE='POWER';
      NO_LOAD_CHECK='Both';
      NO_IO_CHECK='Both';
      NO_ASSERT_CHECK='TRUE';
      NO_DIR_CHECK='TRUE';
      ALLOW_CONNECT='TRUE';
    'TH':
      PIN_NUMBER='(TH)';
      PINUSE='POWER';
      NO_LOAD_CHECK='Both';
      NO_IO_CHECK='Both';
      NO_ASSERT_CHECK='TRUE';
      NO_DIR_CHECK='TRUE';
      ALLOW_CONNECT='TRUE';
  end_pin;
  body
    PART_NAME='INA230AIRGTR';
    BODY_NAME='INA230AIRGTR';
    PHYS_DES_PREFIX='U';
    CLASS='IC';
  end_body;
end_primitive;

END.
